(kicad_pcb
	(version 20260206)
	(generator "pcbnew")
	(generator_version "10.0")
	(general
		(thickness 1.6)
		(legacy_teardrops no)
	)
	(paper "A4")
	(title_block
		(title "9052_F0T_PDB_Converter_Brick_F_V03_1208_1600_OCP.brd")
		(comment 1 "Grand Teton / footprints 487-492 of 578")
	)
	(layers
		(0 "F.Cu" signal "TOP")
		(4 "In1.Cu" signal "GND")
		(6 "In2.Cu" signal "IN1")
		(8 "In3.Cu" signal "GND1")
		(10 "In4.Cu" signal "VCC")
		(12 "In5.Cu" signal "VCC1")
		(14 "In6.Cu" signal "GND2")
		(16 "In7.Cu" signal "IN2")
		(18 "In8.Cu" signal "GND3")
		(2 "B.Cu" signal "BOTTOM")
		(9 "F.Adhes" user "F.Adhesive")
		(11 "B.Adhes" user "B.Adhesive")
		(13 "F.Paste" user "Package Geometry/Pastemask Top")
		(15 "B.Paste" user "Package Geometry/Pastemask Bottom")
		(5 "F.SilkS" user "Ref Des/Silkscreen Top")
		(7 "B.SilkS" user "Ref Des/Silkscreen Bottom")
		(1 "F.Mask" user "Board Geometry/Soldermask Top")
		(3 "B.Mask" user "Board Geometry/Soldermask Bottom")
		(17 "Dwgs.User" user "User.Drawings")
		(19 "Cmts.User" user "User.Comments")
		(21 "Eco1.User" user "User.Eco1")
		(23 "Eco2.User" user "User.Eco2")
		(25 "Edge.Cuts" user "Board Geometry/Outline")
		(27 "Margin" user)
		(31 "F.CrtYd" user "Package Geometry/Place Bound Top")
		(29 "B.CrtYd" user "Package Geometry/Place Bound Bottom")
		(35 "F.Fab" user "Ref Des/Assembly Top")
		(33 "B.Fab" user "Ref Des/Assembly Bottom")
	)
	(footprint ""
		(layer "B.Cu")
		(at 238.76 -70.993 -90)
		(property "Reference" "R67"
			(at 0 0 90)
			(layer "B.SilkS")
			(hide yes)
			(effects
				(font
					(size 1.27 1.27)
				)
				(justify mirror)
			)
		)
		(property "Value" ""
			(at 0 0 90)
			(layer "B.Fab")
			(effects
				(font
					(size 1.27 1.27)
				)
				(justify mirror)
			)
		)
		(duplicate_pad_numbers_are_jumpers no)
		(fp_line
			(start -0.7874 0.4064)
			(end 0.7874 0.4064)
			(stroke
				(width 0.1524)
				(type default)
			)
			(layer "B.SilkS")
		)
		(fp_line
			(start 0.7874 0.4064)
			(end 0.7874 -0.4064)
			(stroke
				(width 0.1524)
				(type default)
			)
			(layer "B.SilkS")
		)
		(fp_line
			(start -0.7874 -0.4064)
			(end -0.7874 0.4064)
			(stroke
				(width 0.1524)
				(type default)
			)
			(layer "B.SilkS")
		)
		(fp_line
			(start 0.7874 -0.4064)
			(end -0.7874 -0.4064)
			(stroke
				(width 0.1524)
				(type default)
			)
			(layer "B.SilkS")
		)
		(fp_line
			(start -0.67945 0.3048)
			(end -0.120396 0.3048)
			(stroke
				(width 0.1)
				(type default)
			)
			(layer "B.Fab")
		)
		(fp_line
			(start -0.120396 0.3048)
			(end -0.120396 0.2794)
			(stroke
				(width 0.1)
				(type default)
			)
			(layer "B.Fab")
		)
		(fp_line
			(start 0.12065 0.3048)
			(end 0.67945 0.3048)
			(stroke
				(width 0.1)
				(type default)
			)
			(layer "B.Fab")
		)
		(fp_line
			(start 0.67945 0.3048)
			(end 0.67945 -0.305054)
			(stroke
				(width 0.1)
				(type default)
			)
			(layer "B.Fab")
		)
		(fp_line
			(start -0.120396 0.2794)
			(end 0.12065 0.2794)
			(stroke
				(width 0.1)
				(type default)
			)
			(layer "B.Fab")
		)
		(fp_line
			(start 0.12065 0.2794)
			(end 0.12065 0.3048)
			(stroke
				(width 0.1)
				(type default)
			)
			(layer "B.Fab")
		)
		(fp_line
			(start -0.12065 -0.2794)
			(end -0.12065 -0.3048)
			(stroke
				(width 0.1)
				(type default)
			)
			(layer "B.Fab")
		)
		(fp_line
			(start 0.12065 -0.2794)
			(end -0.12065 -0.2794)
			(stroke
				(width 0.1)
				(type default)
			)
			(layer "B.Fab")
		)
		(fp_line
			(start -0.67945 -0.3048)
			(end -0.67945 0.3048)
			(stroke
				(width 0.1)
				(type default)
			)
			(layer "B.Fab")
		)
		(fp_line
			(start -0.12065 -0.3048)
			(end -0.67945 -0.3048)
			(stroke
				(width 0.1)
				(type default)
			)
			(layer "B.Fab")
		)
		(fp_line
			(start 0.12065 -0.305054)
			(end 0.12065 -0.2794)
			(stroke
				(width 0.1)
				(type default)
			)
			(layer "B.Fab")
		)
		(fp_line
			(start 0.67945 -0.305054)
			(end 0.12065 -0.305054)
			(stroke
				(width 0.1)
				(type default)
			)
			(layer "B.Fab")
		)
		(pad "1" smd circle
			(at 0.40005 0 90)
			(size 0 0)
			(layers "B.Cu" "B.Mask" "B.Paste")
			(net "SMB_MB_PDB_R_SDA")
		)
		(pad "2" smd circle
			(at -0.40005 0 90)
			(size 0 0)
			(layers "B.Cu" "B.Mask" "B.Paste")
			(net "SMB_MB_PDB_SDA")
		)
	)
	(footprint ""
		(layer "B.Cu")
		(at 54.483 -76.327 180)
		(property "Reference" "R178"
			(at 0 0 0)
			(layer "B.SilkS")
			(hide yes)
			(effects
				(font
					(size 1.27 1.27)
				)
				(justify mirror)
			)
		)
		(property "Value" ""
			(at 0 0 0)
			(layer "B.Fab")
			(effects
				(font
					(size 1.27 1.27)
				)
				(justify mirror)
			)
		)
		(duplicate_pad_numbers_are_jumpers no)
		(fp_line
			(start 0.7874 0.4064)
			(end 0.7874 -0.4064)
			(stroke
				(width 0.1524)
				(type default)
			)
			(layer "B.SilkS")
		)
		(fp_line
			(start 0.7874 -0.4064)
			(end -0.7874 -0.4064)
			(stroke
				(width 0.1524)
				(type default)
			)
			(layer "B.SilkS")
		)
		(fp_line
			(start -0.7874 0.4064)
			(end 0.7874 0.4064)
			(stroke
				(width 0.1524)
				(type default)
			)
			(layer "B.SilkS")
		)
		(fp_line
			(start -0.7874 -0.4064)
			(end -0.7874 0.4064)
			(stroke
				(width 0.1524)
				(type default)
			)
			(layer "B.SilkS")
		)
		(fp_line
			(start 0.67945 0.3048)
			(end 0.67945 -0.305054)
			(stroke
				(width 0.1)
				(type default)
			)
			(layer "B.Fab")
		)
		(fp_line
			(start 0.67945 -0.305054)
			(end 0.12065 -0.305054)
			(stroke
				(width 0.1)
				(type default)
			)
			(layer "B.Fab")
		)
		(fp_line
			(start 0.12065 0.3048)
			(end 0.67945 0.3048)
			(stroke
				(width 0.1)
				(type default)
			)
			(layer "B.Fab")
		)
		(fp_line
			(start 0.12065 0.2794)
			(end 0.12065 0.3048)
			(stroke
				(width 0.1)
				(type default)
			)
			(layer "B.Fab")
		)
		(fp_line
			(start 0.12065 -0.2794)
			(end -0.12065 -0.2794)
			(stroke
				(width 0.1)
				(type default)
			)
			(layer "B.Fab")
		)
		(fp_line
			(start 0.12065 -0.305054)
			(end 0.12065 -0.2794)
			(stroke
				(width 0.1)
				(type default)
			)
			(layer "B.Fab")
		)
		(fp_line
			(start -0.120396 0.3048)
			(end -0.120396 0.2794)
			(stroke
				(width 0.1)
				(type default)
			)
			(layer "B.Fab")
		)
		(fp_line
			(start -0.120396 0.2794)
			(end 0.12065 0.2794)
			(stroke
				(width 0.1)
				(type default)
			)
			(layer "B.Fab")
		)
		(fp_line
			(start -0.12065 -0.2794)
			(end -0.12065 -0.3048)
			(stroke
				(width 0.1)
				(type default)
			)
			(layer "B.Fab")
		)
		(fp_line
			(start -0.12065 -0.3048)
			(end -0.67945 -0.3048)
			(stroke
				(width 0.1)
				(type default)
			)
			(layer "B.Fab")
		)
		(fp_line
			(start -0.67945 0.3048)
			(end -0.120396 0.3048)
			(stroke
				(width 0.1)
				(type default)
			)
			(layer "B.Fab")
		)
		(fp_line
			(start -0.67945 -0.3048)
			(end -0.67945 0.3048)
			(stroke
				(width 0.1)
				(type default)
			)
			(layer "B.Fab")
		)
		(pad "1" smd circle
			(at 0.40005 0)
			(size 0 0)
			(layers "B.Cu" "B.Mask" "B.Paste")
			(net "SMB_P52V_VPDB_SDA")
		)
		(pad "2" smd circle
			(at -0.40005 0)
			(size 0 0)
			(layers "B.Cu" "B.Mask" "B.Paste")
			(net "SMB_BRICK3_SDA")
		)
	)
	(footprint ""
		(layer "B.Cu")
		(at 134.493 -76.327 180)
		(property "Reference" "R164"
			(at 0 0 0)
			(layer "B.SilkS")
			(hide yes)
			(effects
				(font
					(size 1.27 1.27)
				)
				(justify mirror)
			)
		)
		(property "Value" ""
			(at 0 0 0)
			(layer "B.Fab")
			(effects
				(font
					(size 1.27 1.27)
				)
				(justify mirror)
			)
		)
		(duplicate_pad_numbers_are_jumpers no)
		(fp_line
			(start 0.7874 0.4064)
			(end 0.7874 -0.4064)
			(stroke
				(width 0.1524)
				(type default)
			)
			(layer "B.SilkS")
		)
		(fp_line
			(start 0.7874 -0.4064)
			(end -0.7874 -0.4064)
			(stroke
				(width 0.1524)
				(type default)
			)
			(layer "B.SilkS")
		)
		(fp_line
			(start -0.7874 0.4064)
			(end 0.7874 0.4064)
			(stroke
				(width 0.1524)
				(type default)
			)
			(layer "B.SilkS")
		)
		(fp_line
			(start -0.7874 -0.4064)
			(end -0.7874 0.4064)
			(stroke
				(width 0.1524)
				(type default)
			)
			(layer "B.SilkS")
		)
		(fp_line
			(start 0.67945 0.3048)
			(end 0.67945 -0.305054)
			(stroke
				(width 0.1)
				(type default)
			)
			(layer "B.Fab")
		)
		(fp_line
			(start 0.67945 -0.305054)
			(end 0.12065 -0.305054)
			(stroke
				(width 0.1)
				(type default)
			)
			(layer "B.Fab")
		)
		(fp_line
			(start 0.12065 0.3048)
			(end 0.67945 0.3048)
			(stroke
				(width 0.1)
				(type default)
			)
			(layer "B.Fab")
		)
		(fp_line
			(start 0.12065 0.2794)
			(end 0.12065 0.3048)
			(stroke
				(width 0.1)
				(type default)
			)
			(layer "B.Fab")
		)
		(fp_line
			(start 0.12065 -0.2794)
			(end -0.12065 -0.2794)
			(stroke
				(width 0.1)
				(type default)
			)
			(layer "B.Fab")
		)
		(fp_line
			(start 0.12065 -0.305054)
			(end 0.12065 -0.2794)
			(stroke
				(width 0.1)
				(type default)
			)
			(layer "B.Fab")
		)
		(fp_line
			(start -0.120396 0.3048)
			(end -0.120396 0.2794)
			(stroke
				(width 0.1)
				(type default)
			)
			(layer "B.Fab")
		)
		(fp_line
			(start -0.120396 0.2794)
			(end 0.12065 0.2794)
			(stroke
				(width 0.1)
				(type default)
			)
			(layer "B.Fab")
		)
		(fp_line
			(start -0.12065 -0.2794)
			(end -0.12065 -0.3048)
			(stroke
				(width 0.1)
				(type default)
			)
			(layer "B.Fab")
		)
		(fp_line
			(start -0.12065 -0.3048)
			(end -0.67945 -0.3048)
			(stroke
				(width 0.1)
				(type default)
			)
			(layer "B.Fab")
		)
		(fp_line
			(start -0.67945 0.3048)
			(end -0.120396 0.3048)
			(stroke
				(width 0.1)
				(type default)
			)
			(layer "B.Fab")
		)
		(fp_line
			(start -0.67945 -0.3048)
			(end -0.67945 0.3048)
			(stroke
				(width 0.1)
				(type default)
			)
			(layer "B.Fab")
		)
		(pad "1" smd circle
			(at 0.40005 0)
			(size 0 0)
			(layers "B.Cu" "B.Mask" "B.Paste")
			(net "SMB_P52V_VPDB_SDA")
		)
		(pad "2" smd circle
			(at -0.40005 0)
			(size 0 0)
			(layers "B.Cu" "B.Mask" "B.Paste")
			(net "SMB_BRICK0_SDA")
		)
	)
	(footprint ""
		(layer "B.Cu")
		(at 230.759 -79.502 -90)
		(property "Reference" "U5"
			(at 0 -1.87833 270)
			(unlocked yes)
			(layer "B.SilkS")
			(effects
				(font
					(size 0.7874 0.5842)
					(thickness 0.1524)
				)
				(justify left mirror)
			)
		)
		(property "Value" ""
			(at 0 0 90)
			(layer "B.Fab")
			(effects
				(font
					(size 1.27 1.27)
				)
				(justify mirror)
			)
		)
		(duplicate_pad_numbers_are_jumpers no)
		(fp_line
			(start -1.400048 1.100074)
			(end 1.400048 1.100074)
			(stroke
				(width 0.1524)
				(type default)
			)
			(layer "B.SilkS")
		)
		(fp_line
			(start 1.400048 1.100074)
			(end 1.400048 -1.100074)
			(stroke
				(width 0.1524)
				(type default)
			)
			(layer "B.SilkS")
		)
		(fp_line
			(start -1.400048 -1.100074)
			(end -1.400048 1.100074)
			(stroke
				(width 0.1524)
				(type default)
			)
			(layer "B.SilkS")
		)
		(fp_line
			(start -1.400048 -1.100074)
			(end 1.400048 -1.100074)
			(stroke
				(width 0.1524)
				(type default)
			)
			(layer "B.SilkS")
		)
		(fp_poly
			(pts
				(xy 0.874014 -1.336548) (xy 0.366014 -2.352548) (xy 1.382014 -2.352548)
			)
			(stroke
				(width 0)
				(type default)
			)
			(fill yes)
			(layer "B.SilkS")
		)
		(fp_line
			(start -0.674878 1.100074)
			(end 0.674878 1.100074)
			(stroke
				(width 0.1)
				(type default)
			)
			(layer "B.Fab")
		)
		(fp_line
			(start 0.674878 1.100074)
			(end 0.674878 -1.100074)
			(stroke
				(width 0.1)
				(type default)
			)
			(layer "B.Fab")
		)
		(fp_line
			(start -0.674878 -1.100074)
			(end -0.674878 1.100074)
			(stroke
				(width 0.1)
				(type default)
			)
			(layer "B.Fab")
		)
		(fp_line
			(start 0.674878 -1.100074)
			(end -0.674878 -1.100074)
			(stroke
				(width 0.1)
				(type default)
			)
			(layer "B.Fab")
		)
		(fp_poly
			(pts
				(xy 1.590548 -0.649986) (xy 2.606548 -1.157986) (xy 2.606548 -0.141986)
			)
			(stroke
				(width 0)
				(type default)
			)
			(fill yes)
			(layer "B.Fab")
		)
		(pad "1" smd rect
			(at 0.94996 -0.649986 180)
			(size 0.4318 0.6096)
			(layers "B.Cu" "B.Mask" "B.Paste")
			(net "PWRGD_P3V3_AUX_MB_R1")
		)
		(pad "2" smd rect
			(at 0.94996 0 180)
			(size 0.4318 0.6096)
			(layers "B.Cu" "B.Mask" "B.Paste")
			(net "FM_U5_VCC")
		)
		(pad "3" smd rect
			(at 0.94996 0.649986 180)
			(size 0.4318 0.6096)
			(layers "B.Cu" "B.Mask" "B.Paste")
			(net "GND")
		)
		(pad "4" smd rect
			(at -0.94996 0.649986 180)
			(size 0.4318 0.6096)
			(layers "B.Cu" "B.Mask" "B.Paste")
			(net "PWRGD_P3V3_AUX_MB_BUF_R")
		)
		(pad "5" smd rect
			(at -0.94996 -0.649986 180)
			(size 0.4318 0.6096)
			(layers "B.Cu" "B.Mask" "B.Paste")
			(net "P3V3_AUX")
		)
	)
	(footprint ""
		(layer "B.Cu")
		(at 241.808 -95.504 90)
		(property "Reference" "C36"
			(at 0 0 90)
			(layer "B.SilkS")
			(hide yes)
			(effects
				(font
					(size 1.27 1.27)
				)
				(justify mirror)
			)
		)
		(property "Value" ""
			(at 0 0 90)
			(layer "B.Fab")
			(effects
				(font
					(size 1.27 1.27)
				)
				(justify mirror)
			)
		)
		(duplicate_pad_numbers_are_jumpers no)
		(fp_line
			(start 2.2098 -0.9398)
			(end -2.2098 -0.9398)
			(stroke
				(width 0.1524)
				(type default)
			)
			(layer "B.SilkS")
		)
		(fp_line
			(start -2.2098 -0.9398)
			(end -2.2098 0.9398)
			(stroke
				(width 0.1524)
				(type default)
			)
			(layer "B.SilkS")
		)
		(fp_line
			(start 2.2098 0.9398)
			(end 2.2098 -0.9398)
			(stroke
				(width 0.1524)
				(type default)
			)
			(layer "B.SilkS")
		)
		(fp_line
			(start -2.2098 0.9398)
			(end 2.2098 0.9398)
			(stroke
				(width 0.1524)
				(type default)
			)
			(layer "B.SilkS")
		)
		(fp_line
			(start 1.700022 -0.899922)
			(end -1.700022 -0.899922)
			(stroke
				(width 0.1)
				(type default)
			)
			(layer "B.Fab")
		)
		(fp_line
			(start -1.700022 -0.899922)
			(end -1.700022 0.899922)
			(stroke
				(width 0.1)
				(type default)
			)
			(layer "B.Fab")
		)
		(fp_line
			(start 1.700022 0.899922)
			(end 1.700022 -0.899922)
			(stroke
				(width 0.1)
				(type default)
			)
			(layer "B.Fab")
		)
		(fp_line
			(start -1.700022 0.899922)
			(end 1.700022 0.899922)
			(stroke
				(width 0.1)
				(type default)
			)
			(layer "B.Fab")
		)
		(pad "1" smd rect
			(at 1.4732 0 90)
			(size 1.1684 1.5748)
			(layers "B.Cu" "B.Mask" "B.Paste")
			(net "P52V_HS")
		)
		(pad "2" smd rect
			(at -1.4732 0 90)
			(size 1.1684 1.5748)
			(layers "B.Cu" "B.Mask" "B.Paste")
			(net "GND")
		)
	)
	(footprint ""
		(layer "B.Cu")
		(at 289.941 -29.464 -90)
		(property "Reference" "R5916"
			(at 0 0 90)
			(layer "B.SilkS")
			(hide yes)
			(effects
				(font
					(size 1.27 1.27)
				)
				(justify mirror)
			)
		)
		(property "Value" ""
			(at 0 0 90)
			(layer "B.Fab")
			(effects
				(font
					(size 1.27 1.27)
				)
				(justify mirror)
			)
		)
		(duplicate_pad_numbers_are_jumpers no)
		(fp_line
			(start -0.7874 0.4064)
			(end 0.7874 0.4064)
			(stroke
				(width 0.1524)
				(type default)
			)
			(layer "B.SilkS")
		)
		(fp_line
			(start 0.7874 0.4064)
			(end 0.7874 -0.4064)
			(stroke
				(width 0.1524)
				(type default)
			)
			(layer "B.SilkS")
		)
		(fp_line
			(start -0.7874 -0.4064)
			(end -0.7874 0.4064)
			(stroke
				(width 0.1524)
				(type default)
			)
			(layer "B.SilkS")
		)
		(fp_line
			(start 0.7874 -0.4064)
			(end -0.7874 -0.4064)
			(stroke
				(width 0.1524)
				(type default)
			)
			(layer "B.SilkS")
		)
		(fp_line
			(start -0.67945 0.3048)
			(end -0.120396 0.3048)
			(stroke
				(width 0.1)
				(type default)
			)
			(layer "B.Fab")
		)
		(fp_line
			(start -0.120396 0.3048)
			(end -0.120396 0.2794)
			(stroke
				(width 0.1)
				(type default)
			)
			(layer "B.Fab")
		)
		(fp_line
			(start 0.12065 0.3048)
			(end 0.67945 0.3048)
			(stroke
				(width 0.1)
				(type default)
			)
			(layer "B.Fab")
		)
		(fp_line
			(start 0.67945 0.3048)
			(end 0.67945 -0.305054)
			(stroke
				(width 0.1)
				(type default)
			)
			(layer "B.Fab")
		)
		(fp_line
			(start -0.120396 0.2794)
			(end 0.12065 0.2794)
			(stroke
				(width 0.1)
				(type default)
			)
			(layer "B.Fab")
		)
		(fp_line
			(start 0.12065 0.2794)
			(end 0.12065 0.3048)
			(stroke
				(width 0.1)
				(type default)
			)
			(layer "B.Fab")
		)
		(fp_line
			(start -0.12065 -0.2794)
			(end -0.12065 -0.3048)
			(stroke
				(width 0.1)
				(type default)
			)
			(layer "B.Fab")
		)
		(fp_line
			(start 0.12065 -0.2794)
			(end -0.12065 -0.2794)
			(stroke
				(width 0.1)
				(type default)
			)
			(layer "B.Fab")
		)
		(fp_line
			(start -0.67945 -0.3048)
			(end -0.67945 0.3048)
			(stroke
				(width 0.1)
				(type default)
			)
			(layer "B.Fab")
		)
		(fp_line
			(start -0.12065 -0.3048)
			(end -0.67945 -0.3048)
			(stroke
				(width 0.1)
				(type default)
			)
			(layer "B.Fab")
		)
		(fp_line
			(start 0.12065 -0.305054)
			(end 0.12065 -0.2794)
			(stroke
				(width 0.1)
				(type default)
			)
			(layer "B.Fab")
		)
		(fp_line
			(start 0.67945 -0.305054)
			(end 0.12065 -0.305054)
			(stroke
				(width 0.1)
				(type default)
			)
			(layer "B.Fab")
		)
		(pad "1" smd circle
			(at 0.40005 0 90)
			(size 0 0)
			(layers "B.Cu" "B.Mask" "B.Paste")
			(net "FM_AC_PWR_CYCLE_BUF")
		)
		(pad "2" smd circle
			(at -0.40005 0 90)
			(size 0 0)
			(layers "B.Cu" "B.Mask" "B.Paste")
			(net "GND")
		)
	)
)
